(kicad_pcb
	(version 20260206)
	(generator "pcbnew")
	(generator_version "10.0")
	(general
		(thickness 1.6)
		(legacy_teardrops no)
	)
	(paper "A4")
	(title_block
		(title "baseboard — 13948-1b.1110WZS1818.brd")
		(comment 1 "Honey Badger (Wiwynn) / footprints 1321-1325 of 2523")
	)
	(layers
		(0 "F.Cu" signal "TOP")
		(4 "In1.Cu" signal "L2GND")
		(6 "In2.Cu" signal "L3")
		(8 "In3.Cu" signal "L4VCC")
		(10 "In4.Cu" signal "L5VCC")
		(12 "In5.Cu" signal "L6")
		(14 "In6.Cu" signal "L7GND")
		(2 "B.Cu" signal "BOTTOM")
		(9 "F.Adhes" user "F.Adhesive")
		(11 "B.Adhes" user "B.Adhesive")
		(13 "F.Paste" user "Package Geometry/Pastemask Top")
		(15 "B.Paste" user "Package Geometry/Pastemask Bottom")
		(5 "F.SilkS" user "Ref Des/Silkscreen Top")
		(7 "B.SilkS" user "Ref Des/Silkscreen Bottom")
		(1 "F.Mask" user "Board Geometry/Soldermask Top")
		(3 "B.Mask" user "Board Geometry/Soldermask Bottom")
		(17 "Dwgs.User" user "User.Drawings")
		(19 "Cmts.User" user "User.Comments")
		(21 "Eco1.User" user "User.Eco1")
		(23 "Eco2.User" user "User.Eco2")
		(25 "Edge.Cuts" user "Board Geometry/Outline")
		(27 "Margin" user)
		(31 "F.CrtYd" user "Package Geometry/Place Bound Top")
		(29 "B.CrtYd" user "Package Geometry/Place Bound Bottom")
		(35 "F.Fab" user "Ref Des/Assembly Top")
		(33 "B.Fab" user "Ref Des/Assembly Bottom")
	)
	(footprint ""
		(layer "F.Cu")
		(at 266.437872 -39.442136 180)
		(property "Reference" "PU3"
			(at 0 0 180)
			(layer "F.SilkS")
			(hide yes)
			(effects
				(font
					(size 1.27 1.27)
				)
			)
		)
		(property "Value" "TPS53318DQPR-GP"
			(at -5.022088 -6.851904 180)
			(unlocked yes)
			(layer "F.Fab")
			(hide yes)
			(effects
				(font
					(size 1.016 1.016)
					(thickness 0.1524)
				)
			)
		)
		(property "Device Type" "DFN22G6050-G6133H60"
			(at -5.022088 -8.375904 180)
			(unlocked yes)
			(layer "F.Fab")
			(hide yes)
			(effects
				(font
					(size 1.016 1.016)
					(thickness 0.1524)
				)
			)
		)
		(duplicate_pad_numbers_are_jumpers no)
		(fp_line
			(start 3.5052 3.5179)
			(end 3.5052 2.2479)
			(stroke
				(width 0.1524)
				(type default)
			)
			(layer "F.SilkS")
		)
		(fp_line
			(start 2.2352 3.5179)
			(end 3.5052 3.5179)
			(stroke
				(width 0.1524)
				(type default)
			)
			(layer "F.SilkS")
		)
		(fp_line
			(start 1.500124 3.262122)
			(end 1.500124 4.024122)
			(stroke
				(width 0.1524)
				(type default)
			)
			(layer "F.SilkS")
		)
		(fp_line
			(start 0.500126 -3.262122)
			(end 0.500126 -3.770122)
			(stroke
				(width 0.1524)
				(type default)
			)
			(layer "F.SilkS")
		)
		(fp_line
			(start -0.999998 3.262122)
			(end -0.999998 3.770122)
			(stroke
				(width 0.1524)
				(type default)
			)
			(layer "F.SilkS")
		)
		(fp_line
			(start -1.999996 -3.262122)
			(end -1.999996 -4.024122)
			(stroke
				(width 0.1524)
				(type default)
			)
			(layer "F.SilkS")
		)
		(fp_line
			(start -2.2352 -3.5179)
			(end -3.5052 -3.5179)
			(stroke
				(width 0.1524)
				(type default)
			)
			(layer "F.SilkS")
		)
		(fp_line
			(start -3.5052 3.5179)
			(end -2.2352 3.5179)
			(stroke
				(width 0.1524)
				(type default)
			)
			(layer "F.SilkS")
		)
		(fp_line
			(start -3.5052 2.2479)
			(end -3.5052 3.5179)
			(stroke
				(width 0.1524)
				(type default)
			)
			(layer "F.SilkS")
		)
		(fp_line
			(start -3.5052 -3.5179)
			(end -3.5052 -2.2479)
			(stroke
				(width 0.1524)
				(type default)
			)
			(layer "F.SilkS")
		)
		(fp_poly
			(pts
				(xy 3.5052 -3.5179) (xy 2.4765 -3.5179) (xy 3.5052 -2.4892)
			)
			(stroke
				(width 0)
				(type default)
			)
			(fill yes)
			(layer "F.SilkS")
		)
		(fp_rect
			(start -2.9972 2.5019)
			(end 2.9972 -2.5019)
			(stroke
				(width 0)
				(type default)
			)
			(fill no)
			(layer "F.CrtYd")
		)
		(fp_poly
			(pts
				(xy 3.556 -2.5019) (xy -2.9972 -2.5019) (xy -2.9972 2.5019) (xy 2.9972 2.5019) (xy 2.9972 -2.4892)
				(xy 3.556 -2.4892) (xy 3.556 3.5179) (xy -3.556 3.5179) (xy -3.556 -3.5179) (xy 3.556 -3.5179)
			)
			(stroke
				(width 0)
				(type default)
			)
			(fill no)
			(layer "F.CrtYd")
		)
		(fp_rect
			(start -3.556 3.5179)
			(end 3.556 -3.5179)
			(stroke
				(width 0)
				(type default)
			)
			(fill no)
			(layer "F.Fab")
		)
		(pad "1" smd rect
			(at 2.500122 -2.449322 180)
			(size 0.3048 1.1176)
			(layers "F.Cu" "F.Mask" "F.Paste")
			(net "P1V8_STBY_VFB")
		)
		(pad "2" smd rect
			(at 1.999996 -2.449322 180)
			(size 0.3048 1.1176)
			(layers "F.Cu" "F.Mask" "F.Paste")
			(net "P1V8_STBY_EN")
		)
		(pad "3" smd rect
			(at 1.500124 -2.449322 180)
			(size 0.3048 1.1176)
			(layers "F.Cu" "F.Mask" "F.Paste")
			(net "P1V8_STBY_PG")
		)
		(pad "4" smd rect
			(at 0.999998 -2.449322 180)
			(size 0.3048 1.1176)
			(layers "F.Cu" "F.Mask" "F.Paste")
			(net "P1V8_STBY_VBST")
		)
		(pad "5" smd rect
			(at 0.500126 -2.449322 180)
			(size 0.3048 1.1176)
			(layers "F.Cu" "F.Mask" "F.Paste")
			(net "P1V8_STBY_ROVP")
		)
		(pad "6" smd rect
			(at 0 -2.449322 180)
			(size 0.3048 1.1176)
			(layers "F.Cu" "F.Mask" "F.Paste")
			(net "P1V8_STBY_LL")
		)
		(pad "7" smd rect
			(at -0.500126 -2.449322 180)
			(size 0.3048 1.1176)
			(layers "F.Cu" "F.Mask" "F.Paste")
			(net "P1V8_STBY_LL")
		)
		(pad "8" smd rect
			(at -0.999998 -2.449322 180)
			(size 0.3048 1.1176)
			(layers "F.Cu" "F.Mask" "F.Paste")
			(net "P1V8_STBY_LL")
		)
		(pad "9" smd rect
			(at -1.500124 -2.449322 180)
			(size 0.3048 1.1176)
			(layers "F.Cu" "F.Mask" "F.Paste")
			(net "P1V8_STBY_LL")
		)
		(pad "10" smd rect
			(at -1.999996 -2.449322 180)
			(size 0.3048 1.1176)
			(layers "F.Cu" "F.Mask" "F.Paste")
			(net "P1V8_STBY_LL")
		)
		(pad "11" smd rect
			(at -2.500122 -2.449322 180)
			(size 0.3048 1.1176)
			(layers "F.Cu" "F.Mask" "F.Paste")
			(net "P1V8_STBY_LL")
		)
		(pad "12" smd rect
			(at -2.500122 2.449322 180)
			(size 0.3048 1.1176)
			(layers "F.Cu" "F.Mask" "F.Paste")
			(net "P1V8_STBY_VIN")
		)
		(pad "13" smd rect
			(at -1.999996 2.449322 180)
			(size 0.3048 1.1176)
			(layers "F.Cu" "F.Mask" "F.Paste")
			(net "P1V8_STBY_VIN")
		)
		(pad "14" smd rect
			(at -1.500124 2.449322 180)
			(size 0.3048 1.1176)
			(layers "F.Cu" "F.Mask" "F.Paste")
			(net "P1V8_STBY_VIN")
		)
		(pad "15" smd rect
			(at -0.999998 2.449322 180)
			(size 0.3048 1.1176)
			(layers "F.Cu" "F.Mask" "F.Paste")
			(net "P1V8_STBY_VIN")
		)
		(pad "16" smd rect
			(at -0.500126 2.449322 180)
			(size 0.3048 1.1176)
			(layers "F.Cu" "F.Mask" "F.Paste")
			(net "P1V8_STBY_VIN")
		)
		(pad "17" smd rect
			(at 0 2.449322 180)
			(size 0.3048 1.1176)
			(layers "F.Cu" "F.Mask" "F.Paste")
			(net "P1V8_STBY_VIN")
		)
		(pad "18" smd rect
			(at 0.500126 2.449322 180)
			(size 0.3048 1.1176)
			(layers "F.Cu" "F.Mask" "F.Paste")
			(net "P1V8_STBY_VREG")
		)
		(pad "19" smd rect
			(at 0.999998 2.449322 180)
			(size 0.3048 1.1176)
			(layers "F.Cu" "F.Mask" "F.Paste")
			(net "P1V8_STBY_VDD")
		)
		(pad "20" smd rect
			(at 1.500124 2.449322 180)
			(size 0.3048 1.1176)
			(layers "F.Cu" "F.Mask" "F.Paste")
			(net "P1V8_STBY_MODE")
		)
		(pad "21" smd rect
			(at 1.999996 2.449322 180)
			(size 0.3048 1.1176)
			(layers "F.Cu" "F.Mask" "F.Paste")
			(net "P1V8_STBY_TRIP")
		)
		(pad "22" smd rect
			(at 2.500122 2.449322 180)
			(size 0.3048 1.1176)
			(layers "F.Cu" "F.Mask" "F.Paste")
			(net "P1V8_STBY_RF")
		)
		(pad "23" smd custom
			(at 0 0 180)
			(size 0.83185 0.83185)
			(layers "F.Cu" "F.Mask" "F.Paste")
			(net "GND")
			(options
				(clearance outline)
				(anchor circle)
			)
			(primitives
				(gr_poly
					(pts
						(xy -2.7813 1.6637) (xy -2.7813 1.2954) (xy -3.048 1.2954) (xy -3.048 0.9525) (xy -2.7813 0.9525)
						(xy -2.7813 -0.9525) (xy -3.048 -0.9525) (xy -3.048 -1.2954) (xy -2.7813 -1.2954) (xy -2.7813 -1.6637)
						(xy 2.7813 -1.6637) (xy 2.7813 -1.2954) (xy 3.048 -1.2954) (xy 3.048 -0.9525) (xy 2.7813 -0.9525)
						(xy 2.7813 0.9525) (xy 3.048 0.9525) (xy 3.048 1.2954) (xy 2.7813 1.2954) (xy 2.7813 1.6637)
					)
					(width 0)
					(fill yes)
				)
			)
		)
	)
	(footprint ""
		(layer "F.Cu")
		(at 95.89897 -91.948 90)
		(property "Reference" "SR774"
			(at 0 0 90)
			(layer "F.SilkS")
			(hide yes)
			(effects
				(font
					(size 1.27 1.27)
				)
			)
		)
		(property "Value" "34KR2F-GP"
			(at 0.064008 -3.993896 90)
			(unlocked yes)
			(layer "F.Fab")
			(hide yes)
			(effects
				(font
					(size 1.016 1.016)
					(thickness 0.1524)
				)
			)
		)
		(property "Device Type" "R402H16"
			(at 0.064008 -5.517896 90)
			(unlocked yes)
			(layer "F.Fab")
			(hide yes)
			(effects
				(font
					(size 1.016 1.016)
					(thickness 0.1524)
				)
			)
		)
		(duplicate_pad_numbers_are_jumpers no)
		(fp_line
			(start 0.508 -0.9398)
			(end -0.508 -0.9398)
			(stroke
				(width 0.1524)
				(type default)
			)
			(layer "F.SilkS")
		)
		(fp_line
			(start -0.508 -0.9398)
			(end -0.508 0.9398)
			(stroke
				(width 0.1524)
				(type default)
			)
			(layer "F.SilkS")
		)
		(fp_rect
			(start -0.508 0.9398)
			(end 0.508 -0.9398)
			(stroke
				(width 0)
				(type default)
			)
			(fill no)
			(layer "F.CrtYd")
		)
		(fp_rect
			(start -0.508 0.9398)
			(end 0.508 -0.9398)
			(stroke
				(width 0)
				(type default)
			)
			(fill no)
			(layer "F.Fab")
		)
		(pad "1" smd custom
			(at 0 -0.4445 90)
			(size 0.1397 0.1397)
			(layers "F.Cu" "F.Mask" "F.Paste")
			(net "P1V8_E")
			(options
				(clearance outline)
				(anchor circle)
			)
			(primitives
				(gr_poly
					(pts
						(arc
							(start -0.1778 -0.2794)
							(mid -0.249642 -0.249642)
							(end -0.2794 -0.1778)
						)
						(arc
							(start -0.2794 0.1778)
							(mid -0.249642 0.249642)
							(end -0.1778 0.2794)
						)
						(arc
							(start 0.1778 0.2794)
							(mid 0.249642 0.249642)
							(end 0.2794 0.1778)
						)
						(arc
							(start 0.2794 -0.1778)
							(mid 0.249642 -0.249642)
							(end 0.1778 -0.2794)
						)
					)
					(width 0)
					(fill yes)
				)
			)
		)
		(pad "2" smd custom
			(at 0 0.4445 90)
			(size 0.1397 0.1397)
			(layers "F.Cu" "F.Mask" "F.Paste")
			(net "EXP_XM_BUSY_N")
			(options
				(clearance outline)
				(anchor circle)
			)
			(primitives
				(gr_poly
					(pts
						(arc
							(start -0.1778 -0.2794)
							(mid -0.249642 -0.249642)
							(end -0.2794 -0.1778)
						)
						(arc
							(start -0.2794 0.1778)
							(mid -0.249642 0.249642)
							(end -0.1778 0.2794)
						)
						(arc
							(start 0.1778 0.2794)
							(mid 0.249642 0.249642)
							(end 0.2794 0.1778)
						)
						(arc
							(start 0.2794 -0.1778)
							(mid 0.249642 -0.249642)
							(end 0.1778 -0.2794)
						)
					)
					(width 0)
					(fill yes)
				)
			)
		)
	)
	(footprint ""
		(layer "F.Cu")
		(at 331.978 -80.391 90)
		(property "Reference" "R339"
			(at 0 0 90)
			(layer "F.SilkS")
			(hide yes)
			(effects
				(font
					(size 1.27 1.27)
				)
			)
		)
		(property "Value" "3K3R2F-2-GP"
			(at 0.064008 -3.993896 90)
			(unlocked yes)
			(layer "F.Fab")
			(hide yes)
			(effects
				(font
					(size 1.016 1.016)
					(thickness 0.1524)
				)
			)
		)
		(property "Device Type" "R402H16"
			(at 0.064008 -5.517896 90)
			(unlocked yes)
			(layer "F.Fab")
			(hide yes)
			(effects
				(font
					(size 1.016 1.016)
					(thickness 0.1524)
				)
			)
		)
		(duplicate_pad_numbers_are_jumpers no)
		(fp_line
			(start 0.508 -0.9398)
			(end -0.508 -0.9398)
			(stroke
				(width 0.1524)
				(type default)
			)
			(layer "F.SilkS")
		)
		(fp_line
			(start -0.508 -0.9398)
			(end -0.508 0.9398)
			(stroke
				(width 0.1524)
				(type default)
			)
			(layer "F.SilkS")
		)
		(fp_rect
			(start -0.508 0.9398)
			(end 0.508 -0.9398)
			(stroke
				(width 0)
				(type default)
			)
			(fill no)
			(layer "F.CrtYd")
		)
		(fp_rect
			(start -0.508 0.9398)
			(end 0.508 -0.9398)
			(stroke
				(width 0)
				(type default)
			)
			(fill no)
			(layer "F.Fab")
		)
		(pad "1" smd custom
			(at 0 -0.4445 90)
			(size 0.1397 0.1397)
			(layers "F.Cu" "F.Mask" "F.Paste")
			(net "AS_ROMA0_R")
			(options
				(clearance outline)
				(anchor circle)
			)
			(primitives
				(gr_poly
					(pts
						(arc
							(start -0.1778 -0.2794)
							(mid -0.249642 -0.249642)
							(end -0.2794 -0.1778)
						)
						(arc
							(start -0.2794 0.1778)
							(mid -0.249642 0.249642)
							(end -0.1778 0.2794)
						)
						(arc
							(start 0.1778 0.2794)
							(mid 0.249642 0.249642)
							(end 0.2794 0.1778)
						)
						(arc
							(start 0.2794 -0.1778)
							(mid 0.249642 -0.249642)
							(end 0.1778 -0.2794)
						)
					)
					(width 0)
					(fill yes)
				)
			)
		)
		(pad "2" smd custom
			(at 0 0.4445 90)
			(size 0.1397 0.1397)
			(layers "F.Cu" "F.Mask" "F.Paste")
			(net "P3V3_STBY")
			(options
				(clearance outline)
				(anchor circle)
			)
			(primitives
				(gr_poly
					(pts
						(arc
							(start -0.1778 -0.2794)
							(mid -0.249642 -0.249642)
							(end -0.2794 -0.1778)
						)
						(arc
							(start -0.2794 0.1778)
							(mid -0.249642 0.249642)
							(end -0.1778 0.2794)
						)
						(arc
							(start 0.1778 0.2794)
							(mid 0.249642 0.249642)
							(end 0.2794 0.1778)
						)
						(arc
							(start 0.2794 -0.1778)
							(mid 0.249642 -0.249642)
							(end 0.1778 -0.2794)
						)
					)
					(width 0)
					(fill yes)
				)
			)
		)
	)
	(footprint ""
		(layer "F.Cu")
		(at 336.423 -78.232 180)
		(property "Reference" "C333"
			(at 0 0 180)
			(layer "F.SilkS")
			(hide yes)
			(effects
				(font
					(size 1.27 1.27)
				)
			)
		)
		(property "Value" "SCD1U16V2KX-3GP"
			(at 1.1811 -2.7051 180)
			(unlocked yes)
			(layer "F.Fab")
			(hide yes)
			(effects
				(font
					(size 1.016 1.016)
					(thickness 0.1524)
				)
			)
		)
		(property "Device Type" "C402H22"
			(at 1.1811 -4.2291 180)
			(unlocked yes)
			(layer "F.Fab")
			(hide yes)
			(effects
				(font
					(size 1.016 1.016)
					(thickness 0.1524)
				)
			)
		)
		(duplicate_pad_numbers_are_jumpers no)
		(fp_rect
			(start -0.4318 0.9525)
			(end 0.4318 -0.9525)
			(stroke
				(width 0)
				(type default)
			)
			(fill no)
			(layer "F.CrtYd")
		)
		(fp_rect
			(start -0.4318 0.9525)
			(end 0.4318 -0.9525)
			(stroke
				(width 0)
				(type default)
			)
			(fill no)
			(layer "F.Fab")
		)
		(pad "1" smd custom
			(at 0 -0.4445 180)
			(size 0.1524 0.1524)
			(layers "F.Cu" "F.Mask" "F.Paste")
			(net "P3V3_STBY")
			(options
				(clearance outline)
				(anchor circle)
			)
			(primitives
				(gr_poly
					(pts
						(arc
							(start 0.3048 -0.2032)
							(mid 0.275042 -0.275042)
							(end 0.2032 -0.3048)
						)
						(arc
							(start -0.2032 -0.3048)
							(mid -0.275042 -0.275042)
							(end -0.3048 -0.2032)
						)
						(arc
							(start -0.3048 0.2032)
							(mid -0.275042 0.275042)
							(end -0.2032 0.3048)
						)
						(arc
							(start 0.2032 0.3048)
							(mid 0.275042 0.275042)
							(end 0.3048 0.2032)
						)
					)
					(width 0)
					(fill yes)
				)
			)
		)
		(pad "2" smd custom
			(at 0 0.4445 180)
			(size 0.1524 0.1524)
			(layers "F.Cu" "F.Mask" "F.Paste")
			(net "GND")
			(options
				(clearance outline)
				(anchor circle)
			)
			(primitives
				(gr_poly
					(pts
						(arc
							(start 0.3048 -0.2032)
							(mid 0.275042 -0.275042)
							(end 0.2032 -0.3048)
						)
						(arc
							(start -0.2032 -0.3048)
							(mid -0.275042 -0.275042)
							(end -0.3048 -0.2032)
						)
						(arc
							(start -0.3048 0.2032)
							(mid -0.275042 0.275042)
							(end -0.2032 0.3048)
						)
						(arc
							(start 0.2032 0.3048)
							(mid 0.275042 0.275042)
							(end 0.3048 0.2032)
						)
					)
					(width 0)
					(fill yes)
				)
			)
		)
	)
	(footprint ""
		(layer "F.Cu")
		(at 173.981872 -203.830936 90)
		(property "Reference" "R423"
			(at 0 0 90)
			(layer "F.SilkS")
			(hide yes)
			(effects
				(font
					(size 1.27 1.27)
				)
			)
		)
		(property "Value" "4K7R2J-2-GP"
			(at 0.064008 -3.993896 90)
			(unlocked yes)
			(layer "F.Fab")
			(hide yes)
			(effects
				(font
					(size 1.016 1.016)
					(thickness 0.1524)
				)
			)
		)
		(property "Device Type" "R402H16"
			(at 0.064008 -5.517896 90)
			(unlocked yes)
			(layer "F.Fab")
			(hide yes)
			(effects
				(font
					(size 1.016 1.016)
					(thickness 0.1524)
				)
			)
		)
		(duplicate_pad_numbers_are_jumpers no)
		(fp_line
			(start 0.508 -0.9398)
			(end -0.508 -0.9398)
			(stroke
				(width 0.1524)
				(type default)
			)
			(layer "F.SilkS")
		)
		(fp_line
			(start -0.508 -0.9398)
			(end -0.508 0.9398)
			(stroke
				(width 0.1524)
				(type default)
			)
			(layer "F.SilkS")
		)
		(fp_rect
			(start -0.508 0.9398)
			(end 0.508 -0.9398)
			(stroke
				(width 0)
				(type default)
			)
			(fill no)
			(layer "F.CrtYd")
		)
		(fp_rect
			(start -0.508 0.9398)
			(end 0.508 -0.9398)
			(stroke
				(width 0)
				(type default)
			)
			(fill no)
			(layer "F.Fab")
		)
		(pad "1" smd custom
			(at 0 -0.4445 90)
			(size 0.1397 0.1397)
			(layers "F.Cu" "F.Mask" "F.Paste")
			(net "P3V3_STBY")
			(options
				(clearance outline)
				(anchor circle)
			)
			(primitives
				(gr_poly
					(pts
						(arc
							(start -0.1778 -0.2794)
							(mid -0.249642 -0.249642)
							(end -0.2794 -0.1778)
						)
						(arc
							(start -0.2794 0.1778)
							(mid -0.249642 0.249642)
							(end -0.1778 0.2794)
						)
						(arc
							(start 0.1778 0.2794)
							(mid 0.249642 0.249642)
							(end 0.2794 0.1778)
						)
						(arc
							(start 0.2794 -0.1778)
							(mid 0.249642 -0.249642)
							(end 0.1778 -0.2794)
						)
					)
					(width 0)
					(fill yes)
				)
			)
		)
		(pad "2" smd custom
			(at 0 0.4445 90)
			(size 0.1397 0.1397)
			(layers "F.Cu" "F.Mask" "F.Paste")
			(net "SAS_I2C_B_BUF_SCL")
			(options
				(clearance outline)
				(anchor circle)
			)
			(primitives
				(gr_poly
					(pts
						(arc
							(start -0.1778 -0.2794)
							(mid -0.249642 -0.249642)
							(end -0.2794 -0.1778)
						)
						(arc
							(start -0.2794 0.1778)
							(mid -0.249642 0.249642)
							(end -0.1778 0.2794)
						)
						(arc
							(start 0.1778 0.2794)
							(mid 0.249642 0.249642)
							(end 0.2794 0.1778)
						)
						(arc
							(start 0.2794 -0.1778)
							(mid 0.249642 -0.249642)
							(end 0.1778 -0.2794)
						)
					)
					(width 0)
					(fill yes)
				)
			)
		)
	)
)
